# T6G (Grand Teton) — schematic netlist excerpt (pin names and nets, part order shuffled) for the footprints in the layout excerpt that follows; sources: Cadence DE-HDL packaged netlist, KiCad conversion of 04192023_DAF0TMB3IC0_F0TG_MB_C_brd_V02_OCP.brd

C2662  Q_CAP  10UF 6.3V 20% X6S  pkg C0402  page 75 : A = PVDD_33_S5 ; B = GND
C1021  Q_CAP  0.1UF 10V 10% X7S  pkg C0201  page 312 : A = P0V9_CPU0_RT3_2A_2D ; B = GND
C2022  Q_CAP  0.1UF 25V 10% X7R  pkg 0402  page 237 : A = VSENSE_P12V_INA230_5_INP ; B = VSENSE_P12V_INA230_5_INN

(kicad_pcb
	(version 20260206)
	(generator "pcbnew")
	(generator_version "10.0")
	(general
		(thickness 1.6)
		(legacy_teardrops no)
	)
	(paper "A4")
	(title_block
		(title "04192023_DAF0TMB3IC0_F0TG_MB_C_brd_V02_OCP.brd")
		(comment 1 "Grand Teton / footprints 6105-6107 of 8354")
	)
	(layers
		(0 "F.Cu" signal "TOP")
		(4 "In1.Cu" signal "GND")
		(6 "In2.Cu" signal "IN1")
		(8 "In3.Cu" signal "GND1")
		(10 "In4.Cu" signal "IN2")
		(12 "In5.Cu" signal "GND2")
		(14 "In6.Cu" signal "IN3")
		(16 "In7.Cu" signal "GND3")
		(18 "In8.Cu" signal "VCC")
		(20 "In9.Cu" signal "VCC1")
		(22 "In10.Cu" signal "GND4")
		(24 "In11.Cu" signal "IN4")
		(26 "In12.Cu" signal "GND5")
		(28 "In13.Cu" signal "IN5")
		(30 "In14.Cu" signal "GND6")
		(32 "In15.Cu" signal "IN6")
		(34 "In16.Cu" signal "GND7")
		(2 "B.Cu" signal "BOTTOM")
		(9 "F.Adhes" user "F.Adhesive")
		(11 "B.Adhes" user "B.Adhesive")
		(13 "F.Paste" user "Package Geometry/Pastemask Top")
		(15 "B.Paste" user "Package Geometry/Pastemask Bottom")
		(5 "F.SilkS" user "Ref Des/Silkscreen Top")
		(7 "B.SilkS" user "Ref Des/Silkscreen Bottom")
		(1 "F.Mask" user "Board Geometry/Soldermask Top")
		(3 "B.Mask" user "Board Geometry/Soldermask Bottom")
		(17 "Dwgs.User" user "User.Drawings")
		(19 "Cmts.User" user "User.Comments")
		(21 "Eco1.User" user "User.Eco1")
		(23 "Eco2.User" user "User.Eco2")
		(25 "Edge.Cuts" user "Board Geometry/Outline")
		(27 "Margin" user)
		(31 "F.CrtYd" user "Package Geometry/Place Bound Top")
		(29 "B.CrtYd" user "Package Geometry/Place Bound Bottom")
		(35 "F.Fab" user "Ref Des/Assembly Top")
		(33 "B.Fab" user "Ref Des/Assembly Bottom")
	)
	(footprint ""
		(layer "B.Cu")
		(at 98.962464 -267.529564)
		(property "Reference" "C2662"
			(at 0 0 0)
			(layer "B.SilkS")
			(hide yes)
			(effects
				(font
					(size 1.27 1.27)
				)
				(justify mirror)
			)
		)
		(property "Value" ""
			(at 0 0 0)
			(layer "B.Fab")
			(effects
				(font
					(size 1.27 1.27)
				)
				(justify mirror)
			)
		)
		(duplicate_pad_numbers_are_jumpers no)
		(fp_line
			(start -0.7874 -0.4064)
			(end -0.7874 0.4064)
			(stroke
				(width 0.1524)
				(type default)
			)
			(layer "B.SilkS")
		)
		(fp_line
			(start -0.7874 0.4064)
			(end 0.7874 0.4064)
			(stroke
				(width 0.1524)
				(type default)
			)
			(layer "B.SilkS")
		)
		(fp_line
			(start 0.7874 -0.4064)
			(end -0.7874 -0.4064)
			(stroke
				(width 0.1524)
				(type default)
			)
			(layer "B.SilkS")
		)
		(fp_line
			(start 0.7874 0.4064)
			(end 0.7874 -0.4064)
			(stroke
				(width 0.1524)
				(type default)
			)
			(layer "B.SilkS")
		)
		(fp_line
			(start -0.67945 -0.3048)
			(end -0.67945 0.3048)
			(stroke
				(width 0.1)
				(type default)
			)
			(layer "B.Fab")
		)
		(fp_line
			(start -0.67945 0.3048)
			(end -0.120396 0.3048)
			(stroke
				(width 0.1)
				(type default)
			)
			(layer "B.Fab")
		)
		(fp_line
			(start -0.12065 -0.3048)
			(end -0.67945 -0.3048)
			(stroke
				(width 0.1)
				(type default)
			)
			(layer "B.Fab")
		)
		(fp_line
			(start -0.12065 -0.2794)
			(end -0.12065 -0.3048)
			(stroke
				(width 0.1)
				(type default)
			)
			(layer "B.Fab")
		)
		(fp_line
			(start -0.120396 0.2794)
			(end 0.12065 0.2794)
			(stroke
				(width 0.1)
				(type default)
			)
			(layer "B.Fab")
		)
		(fp_line
			(start -0.120396 0.3048)
			(end -0.120396 0.2794)
			(stroke
				(width 0.1)
				(type default)
			)
			(layer "B.Fab")
		)
		(fp_line
			(start 0.12065 -0.305054)
			(end 0.12065 -0.2794)
			(stroke
				(width 0.1)
				(type default)
			)
			(layer "B.Fab")
		)
		(fp_line
			(start 0.12065 -0.2794)
			(end -0.12065 -0.2794)
			(stroke
				(width 0.1)
				(type default)
			)
			(layer "B.Fab")
		)
		(fp_line
			(start 0.12065 0.2794)
			(end 0.12065 0.3048)
			(stroke
				(width 0.1)
				(type default)
			)
			(layer "B.Fab")
		)
		(fp_line
			(start 0.12065 0.3048)
			(end 0.67945 0.3048)
			(stroke
				(width 0.1)
				(type default)
			)
			(layer "B.Fab")
		)
		(fp_line
			(start 0.67945 -0.305054)
			(end 0.12065 -0.305054)
			(stroke
				(width 0.1)
				(type default)
			)
			(layer "B.Fab")
		)
		(fp_line
			(start 0.67945 0.3048)
			(end 0.67945 -0.305054)
			(stroke
				(width 0.1)
				(type default)
			)
			(layer "B.Fab")
		)
		(pad "1" smd circle
			(at 0.40005 0 180)
			(size 0 0)
			(layers "B.Cu" "B.Mask" "B.Paste")
			(net "PVDD_33_S5")
		)
		(pad "2" smd circle
			(at -0.40005 0 180)
			(size 0 0)
			(layers "B.Cu" "B.Mask" "B.Paste")
			(net "GND")
		)
	)
	(footprint ""
		(layer "B.Cu")
		(at 375.41835 -396.393162 -90)
		(property "Reference" "C1021"
			(at 0 0 90)
			(layer "B.SilkS")
			(hide yes)
			(effects
				(font
					(size 1.27 1.27)
				)
				(justify mirror)
			)
		)
		(property "Value" ""
			(at 0 0 90)
			(layer "B.Fab")
			(effects
				(font
					(size 1.27 1.27)
				)
				(justify mirror)
			)
		)
		(duplicate_pad_numbers_are_jumpers no)
		(fp_line
			(start -0.299974 0.150114)
			(end 0.299974 0.150114)
			(stroke
				(width 0.1)
				(type default)
			)
			(layer "B.Fab")
		)
		(fp_line
			(start 0.299974 0.150114)
			(end 0.299974 -0.150114)
			(stroke
				(width 0.1)
				(type default)
			)
			(layer "B.Fab")
		)
		(fp_line
			(start -0.299974 -0.150114)
			(end -0.299974 0.150114)
			(stroke
				(width 0.1)
				(type default)
			)
			(layer "B.Fab")
		)
		(fp_line
			(start 0.299974 -0.150114)
			(end -0.299974 -0.150114)
			(stroke
				(width 0.1)
				(type default)
			)
			(layer "B.Fab")
		)
		(pad "1" smd rect
			(at 0.2667 0 90)
			(size 0.3048 0.381)
			(layers "B.Cu" "B.Mask" "B.Paste")
			(net "P0V9_CPU0_RT3_2A_2D")
		)
		(pad "2" smd rect
			(at -0.2667 0 90)
			(size 0.3048 0.381)
			(layers "B.Cu" "B.Mask" "B.Paste")
			(net "GND")
		)
	)
	(footprint ""
		(layer "B.Cu")
		(at 205.28788 -35.956748 90)
		(property "Reference" "C2022"
			(at 0 0 90)
			(layer "B.SilkS")
			(hide yes)
			(effects
				(font
					(size 1.27 1.27)
				)
				(justify mirror)
			)
		)
		(property "Value" ""
			(at 0 0 90)
			(layer "B.Fab")
			(effects
				(font
					(size 1.27 1.27)
				)
				(justify mirror)
			)
		)
		(duplicate_pad_numbers_are_jumpers no)
		(fp_line
			(start 0.7874 -0.4064)
			(end -0.7874 -0.4064)
			(stroke
				(width 0.1524)
				(type default)
			)
			(layer "B.SilkS")
		)
		(fp_line
			(start -0.7874 -0.4064)
			(end -0.7874 0.4064)
			(stroke
				(width 0.1524)
				(type default)
			)
			(layer "B.SilkS")
		)
		(fp_line
			(start 0.7874 0.4064)
			(end 0.7874 -0.4064)
			(stroke
				(width 0.1524)
				(type default)
			)
			(layer "B.SilkS")
		)
		(fp_line
			(start -0.7874 0.4064)
			(end 0.7874 0.4064)
			(stroke
				(width 0.1524)
				(type default)
			)
			(layer "B.SilkS")
		)
		(fp_line
			(start 0.67945 -0.305054)
			(end 0.12065 -0.305054)
			(stroke
				(width 0.1)
				(type default)
			)
			(layer "B.Fab")
		)
		(fp_line
			(start 0.12065 -0.305054)
			(end 0.12065 -0.2794)
			(stroke
				(width 0.1)
				(type default)
			)
			(layer "B.Fab")
		)
		(fp_line
			(start -0.12065 -0.3048)
			(end -0.67945 -0.3048)
			(stroke
				(width 0.1)
				(type default)
			)
			(layer "B.Fab")
		)
		(fp_line
			(start -0.67945 -0.3048)
			(end -0.67945 0.3048)
			(stroke
				(width 0.1)
				(type default)
			)
			(layer "B.Fab")
		)
		(fp_line
			(start 0.12065 -0.2794)
			(end -0.12065 -0.2794)
			(stroke
				(width 0.1)
				(type default)
			)
			(layer "B.Fab")
		)
		(fp_line
			(start -0.12065 -0.2794)
			(end -0.12065 -0.3048)
			(stroke
				(width 0.1)
				(type default)
			)
			(layer "B.Fab")
		)
		(fp_line
			(start 0.12065 0.2794)
			(end 0.12065 0.3048)
			(stroke
				(width 0.1)
				(type default)
			)
			(layer "B.Fab")
		)
		(fp_line
			(start -0.120396 0.2794)
			(end 0.12065 0.2794)
			(stroke
				(width 0.1)
				(type default)
			)
			(layer "B.Fab")
		)
		(fp_line
			(start 0.67945 0.3048)
			(end 0.67945 -0.305054)
			(stroke
				(width 0.1)
				(type default)
			)
			(layer "B.Fab")
		)
		(fp_line
			(start 0.12065 0.3048)
			(end 0.67945 0.3048)
			(stroke
				(width 0.1)
				(type default)
			)
			(layer "B.Fab")
		)
		(fp_line
			(start -0.120396 0.3048)
			(end -0.120396 0.2794)
			(stroke
				(width 0.1)
				(type default)
			)
			(layer "B.Fab")
		)
		(fp_line
			(start -0.67945 0.3048)
			(end -0.120396 0.3048)
			(stroke
				(width 0.1)
				(type default)
			)
			(layer "B.Fab")
		)
		(pad "1" smd circle
			(at 0.40005 0 270)
			(size 0 0)
			(layers "B.Cu" "B.Mask" "B.Paste")
			(net "VSENSE_P12V_INA230_5_INP")
		)
		(pad "2" smd circle
			(at -0.40005 0 270)
			(size 0 0)
			(layers "B.Cu" "B.Mask" "B.Paste")
			(net "VSENSE_P12V_INA230_5_INN")
		)
	)
)
